# S9S_MB_2U (Grand Teton) — schematic netlist excerpt (pin names and nets, part order shuffled) for the footprints in the layout excerpt that follows; sources: Cadence DE-HDL packaged netlist, KiCad conversion of 03242023_DA0F0TMBIJ0_F0T_Motherboard_J_brd_V01_OCP.brd

PC1276  Q_CAP  100NF 50V 10% X7R  pkg C0402  page 282 : A = PVNN_MAIN_CPU0 ; B = GND

Q151  MOSFET_NCH_DUAL  PJT138K IC  pkg SOT363XD  page 144
  S1  = GND
  G1  = PRSNT_SWB_N
  D2  = PRSNT_SWB_ISO_N
  S2  = GND
  G2  = PRSNT_SWB
  D1  = PRSNT_SWB

(kicad_pcb
	(version 20260206)
	(generator "pcbnew")
	(generator_version "10.0")
	(general
		(thickness 1.6)
		(legacy_teardrops no)
	)
	(paper "A4")
	(title_block
		(title "03242023_DA0F0TMBIJ0_F0T_Motherboard_J_brd_V01_OCP.brd")
		(comment 1 "Grand Teton / footprints 3280-3281 of 6105")
	)
	(layers
		(0 "F.Cu" signal "TOP")
		(4 "In1.Cu" signal "GND")
		(6 "In2.Cu" signal "IN1")
		(8 "In3.Cu" signal "GND1")
		(10 "In4.Cu" signal "IN2")
		(12 "In5.Cu" signal "GND2")
		(14 "In6.Cu" signal "IN3")
		(16 "In7.Cu" signal "GND3")
		(18 "In8.Cu" signal "VCC")
		(20 "In9.Cu" signal "VCC1")
		(22 "In10.Cu" signal "GND4")
		(24 "In11.Cu" signal "IN4")
		(26 "In12.Cu" signal "GND5")
		(28 "In13.Cu" signal "IN5")
		(30 "In14.Cu" signal "GND6")
		(32 "In15.Cu" signal "IN6")
		(34 "In16.Cu" signal "GND7")
		(2 "B.Cu" signal "BOTTOM")
		(9 "F.Adhes" user "F.Adhesive")
		(11 "B.Adhes" user "B.Adhesive")
		(13 "F.Paste" user "Package Geometry/Pastemask Top")
		(15 "B.Paste" user "Package Geometry/Pastemask Bottom")
		(5 "F.SilkS" user "Ref Des/Silkscreen Top")
		(7 "B.SilkS" user "Ref Des/Silkscreen Bottom")
		(1 "F.Mask" user "Board Geometry/Soldermask Top")
		(3 "B.Mask" user "Board Geometry/Soldermask Bottom")
		(17 "Dwgs.User" user "User.Drawings")
		(19 "Cmts.User" user "User.Comments")
		(21 "Eco1.User" user "User.Eco1")
		(23 "Eco2.User" user "User.Eco2")
		(25 "Edge.Cuts" user "Board Geometry/Outline")
		(27 "Margin" user)
		(31 "F.CrtYd" user "Package Geometry/Place Bound Top")
		(29 "B.CrtYd" user "Package Geometry/Place Bound Bottom")
		(35 "F.Fab" user "Ref Des/Assembly Top")
		(33 "B.Fab" user "Ref Des/Assembly Bottom")
	)
	(footprint ""
		(layer "F.Cu")
		(at 107.3658 -408.686)
		(property "Reference" "Q151"
			(at 2.76098 0.738632 0)
			(unlocked yes)
			(layer "F.SilkS")
			(effects
				(font
					(size 0.7874 0.5842)
					(thickness 0.1524)
				)
				(justify left)
			)
		)
		(property "Value" ""
			(at 0 0 0)
			(layer "F.Fab")
			(effects
				(font
					(size 1.27 1.27)
				)
			)
		)
		(duplicate_pad_numbers_are_jumpers no)
		(fp_line
			(start -1.332738 -1.100074)
			(end -0.4826 -1.100074)
			(stroke
				(width 0.1524)
				(type default)
			)
			(layer "F.SilkS")
		)
		(fp_line
			(start -1.332738 1.100074)
			(end -1.332738 -1.100074)
			(stroke
				(width 0.1524)
				(type default)
			)
			(layer "F.SilkS")
		)
		(fp_line
			(start -0.4826 -1.100074)
			(end 0 -0.541274)
			(stroke
				(width 0.1524)
				(type default)
			)
			(layer "F.SilkS")
		)
		(fp_line
			(start 0 -0.541274)
			(end 0.4826 -1.100074)
			(stroke
				(width 0.1524)
				(type default)
			)
			(layer "F.SilkS")
		)
		(fp_line
			(start 0.4826 -1.100074)
			(end 1.332738 -1.100074)
			(stroke
				(width 0.1524)
				(type default)
			)
			(layer "F.SilkS")
		)
		(fp_line
			(start 1.332738 -1.100074)
			(end 1.332738 1.100074)
			(stroke
				(width 0.1524)
				(type default)
			)
			(layer "F.SilkS")
		)
		(fp_line
			(start 1.332738 1.100074)
			(end -1.332738 1.100074)
			(stroke
				(width 0.1524)
				(type default)
			)
			(layer "F.SilkS")
		)
		(fp_poly
			(pts
				(xy -2.2352 -0.298958) (xy -2.2352 -1.001014) (xy -1.533144 -0.649986)
			)
			(stroke
				(width 0)
				(type default)
			)
			(fill yes)
			(layer "F.SilkS")
		)
		(fp_line
			(start -0.674878 -1.100074)
			(end 0.674878 -1.100074)
			(stroke
				(width 0.1)
				(type default)
			)
			(layer "F.Fab")
		)
		(fp_line
			(start -0.674878 1.100074)
			(end -0.674878 -1.100074)
			(stroke
				(width 0.1)
				(type default)
			)
			(layer "F.Fab")
		)
		(fp_line
			(start 0.674878 -1.100074)
			(end 0.674878 1.100074)
			(stroke
				(width 0.1)
				(type default)
			)
			(layer "F.Fab")
		)
		(fp_line
			(start 0.674878 1.100074)
			(end -0.674878 1.100074)
			(stroke
				(width 0.1)
				(type default)
			)
			(layer "F.Fab")
		)
		(fp_poly
			(pts
				(xy -2.2352 -0.298958) (xy -2.2352 -1.001014) (xy -1.533144 -0.649986)
			)
			(stroke
				(width 0)
				(type default)
			)
			(fill yes)
			(layer "F.Fab")
		)
		(pad "1" smd rect
			(at -0.94996 -0.649986 90)
			(size 0.4318 0.508)
			(layers "F.Cu" "F.Mask" "F.Paste")
			(net "GND")
		)
		(pad "2" smd rect
			(at -0.94996 0 90)
			(size 0.4318 0.508)
			(layers "F.Cu" "F.Mask" "F.Paste")
			(net "PRSNT_SWB_N")
		)
		(pad "3" smd rect
			(at -0.94996 0.649986 90)
			(size 0.4318 0.508)
			(layers "F.Cu" "F.Mask" "F.Paste")
			(net "PRSNT_SWB_ISO_N")
		)
		(pad "4" smd rect
			(at 0.94996 0.649986 90)
			(size 0.4318 0.508)
			(layers "F.Cu" "F.Mask" "F.Paste")
			(net "GND")
		)
		(pad "5" smd rect
			(at 0.94996 0 90)
			(size 0.4318 0.508)
			(layers "F.Cu" "F.Mask" "F.Paste")
			(net "PRSNT_SWB")
		)
		(pad "6" smd rect
			(at 0.94996 -0.649986 90)
			(size 0.4318 0.508)
			(layers "F.Cu" "F.Mask" "F.Paste")
			(net "PRSNT_SWB")
		)
	)
	(footprint ""
		(layer "F.Cu")
		(at 446.851024 -175.956468)
		(property "Reference" "PC1276"
			(at 0 0 0)
			(layer "F.SilkS")
			(hide yes)
			(effects
				(font
					(size 1.27 1.27)
				)
			)
		)
		(property "Value" ""
			(at 0 0 0)
			(layer "F.Fab")
			(effects
				(font
					(size 1.27 1.27)
				)
			)
		)
		(duplicate_pad_numbers_are_jumpers no)
		(fp_line
			(start -0.7874 -0.4064)
			(end 0.7874 -0.4064)
			(stroke
				(width 0.1524)
				(type default)
			)
			(layer "F.SilkS")
		)
		(fp_line
			(start -0.7874 0.4064)
			(end -0.7874 -0.4064)
			(stroke
				(width 0.1524)
				(type default)
			)
			(layer "F.SilkS")
		)
		(fp_line
			(start 0.7874 -0.4064)
			(end 0.7874 0.4064)
			(stroke
				(width 0.1524)
				(type default)
			)
			(layer "F.SilkS")
		)
		(fp_line
			(start 0.7874 0.4064)
			(end -0.7874 0.4064)
			(stroke
				(width 0.1524)
				(type default)
			)
			(layer "F.SilkS")
		)
		(fp_line
			(start -0.67945 -0.305054)
			(end -0.12065 -0.305054)
			(stroke
				(width 0.1)
				(type default)
			)
			(layer "F.Fab")
		)
		(fp_line
			(start -0.67945 0.3048)
			(end -0.67945 -0.305054)
			(stroke
				(width 0.1)
				(type default)
			)
			(layer "F.Fab")
		)
		(fp_line
			(start -0.12065 -0.305054)
			(end -0.12065 -0.2794)
			(stroke
				(width 0.1)
				(type default)
			)
			(layer "F.Fab")
		)
		(fp_line
			(start -0.12065 -0.2794)
			(end 0.12065 -0.2794)
			(stroke
				(width 0.1)
				(type default)
			)
			(layer "F.Fab")
		)
		(fp_line
			(start -0.12065 0.2794)
			(end -0.12065 0.3048)
			(stroke
				(width 0.1)
				(type default)
			)
			(layer "F.Fab")
		)
		(fp_line
			(start -0.12065 0.3048)
			(end -0.67945 0.3048)
			(stroke
				(width 0.1)
				(type default)
			)
			(layer "F.Fab")
		)
		(fp_line
			(start 0.120396 0.2794)
			(end -0.12065 0.2794)
			(stroke
				(width 0.1)
				(type default)
			)
			(layer "F.Fab")
		)
		(fp_line
			(start 0.120396 0.3048)
			(end 0.120396 0.2794)
			(stroke
				(width 0.1)
				(type default)
			)
			(layer "F.Fab")
		)
		(fp_line
			(start 0.12065 -0.3048)
			(end 0.67945 -0.3048)
			(stroke
				(width 0.1)
				(type default)
			)
			(layer "F.Fab")
		)
		(fp_line
			(start 0.12065 -0.2794)
			(end 0.12065 -0.3048)
			(stroke
				(width 0.1)
				(type default)
			)
			(layer "F.Fab")
		)
		(fp_line
			(start 0.67945 -0.3048)
			(end 0.67945 0.3048)
			(stroke
				(width 0.1)
				(type default)
			)
			(layer "F.Fab")
		)
		(fp_line
			(start 0.67945 0.3048)
			(end 0.120396 0.3048)
			(stroke
				(width 0.1)
				(type default)
			)
			(layer "F.Fab")
		)
		(pad "1" smd circle
			(at -0.40005 0)
			(size 0 0)
			(layers "F.Cu" "F.Mask" "F.Paste")
			(net "PVNN_MAIN_CPU0")
		)
		(pad "2" smd circle
			(at 0.40005 0)
			(size 0 0)
			(layers "F.Cu" "F.Mask" "F.Paste")
			(net "GND")
		)
	)
)
